# T6G (Grand Teton) — schematic netlist excerpt (pin names and nets, part order shuffled) for the footprints in the layout excerpt that follows; sources: Cadence DE-HDL packaged netlist, KiCad conversion of 04192023_DAF0TMB3IC0_F0TG_MB_C_brd_V02_OCP.brd

C96  Q_CAP  0.1UF 25V 10% X7R  pkg 0402  page 88 : A = P3V3_AUX ; B = GND
C971  Q_CAP  10UF 6.3V 20% X6S  pkg C0402  page 301 : A = P0V9_CPU0_RT_2D ; B = GND
R1390  Q_RES  4.7K 5% CHIP  pkg 0201LF  page 185 : A = P1V8_CPU1_RT_1D ; B = SMB_RT_CPU1_P0_ROM_MUX_2D_R_SCL

(kicad_pcb
	(version 20260206)
	(generator "pcbnew")
	(generator_version "10.0")
	(general
		(thickness 1.6)
		(legacy_teardrops no)
	)
	(paper "A4")
	(title_block
		(title "04192023_DAF0TMB3IC0_F0TG_MB_C_brd_V02_OCP.brd")
		(comment 1 "Grand Teton / footprints 5345-5347 of 8354")
	)
	(layers
		(0 "F.Cu" signal "TOP")
		(4 "In1.Cu" signal "GND")
		(6 "In2.Cu" signal "IN1")
		(8 "In3.Cu" signal "GND1")
		(10 "In4.Cu" signal "IN2")
		(12 "In5.Cu" signal "GND2")
		(14 "In6.Cu" signal "IN3")
		(16 "In7.Cu" signal "GND3")
		(18 "In8.Cu" signal "VCC")
		(20 "In9.Cu" signal "VCC1")
		(22 "In10.Cu" signal "GND4")
		(24 "In11.Cu" signal "IN4")
		(26 "In12.Cu" signal "GND5")
		(28 "In13.Cu" signal "IN5")
		(30 "In14.Cu" signal "GND6")
		(32 "In15.Cu" signal "IN6")
		(34 "In16.Cu" signal "GND7")
		(2 "B.Cu" signal "BOTTOM")
		(9 "F.Adhes" user "F.Adhesive")
		(11 "B.Adhes" user "B.Adhesive")
		(13 "F.Paste" user "Package Geometry/Pastemask Top")
		(15 "B.Paste" user "Package Geometry/Pastemask Bottom")
		(5 "F.SilkS" user "Ref Des/Silkscreen Top")
		(7 "B.SilkS" user "Ref Des/Silkscreen Bottom")
		(1 "F.Mask" user "Board Geometry/Soldermask Top")
		(3 "B.Mask" user "Board Geometry/Soldermask Bottom")
		(17 "Dwgs.User" user "User.Drawings")
		(19 "Cmts.User" user "User.Comments")
		(21 "Eco1.User" user "User.Eco1")
		(23 "Eco2.User" user "User.Eco2")
		(25 "Edge.Cuts" user "Board Geometry/Outline")
		(27 "Margin" user)
		(31 "F.CrtYd" user "Package Geometry/Place Bound Top")
		(29 "B.CrtYd" user "Package Geometry/Place Bound Bottom")
		(35 "F.Fab" user "Ref Des/Assembly Top")
		(33 "B.Fab" user "Ref Des/Assembly Bottom")
	)
	(footprint ""
		(layer "B.Cu")
		(at 239.903 -335.026)
		(property "Reference" "R1390"
			(at 0 0 0)
			(layer "B.SilkS")
			(hide yes)
			(effects
				(font
					(size 1.27 1.27)
				)
				(justify mirror)
			)
		)
		(property "Value" ""
			(at 0 0 0)
			(layer "B.Fab")
			(effects
				(font
					(size 1.27 1.27)
				)
				(justify mirror)
			)
		)
		(duplicate_pad_numbers_are_jumpers no)
		(fp_line
			(start -0.32512 -0.175006)
			(end -0.32512 0.175006)
			(stroke
				(width 0.1)
				(type default)
			)
			(layer "B.Fab")
		)
		(fp_line
			(start -0.32512 0.175006)
			(end 0.32512 0.175006)
			(stroke
				(width 0.1)
				(type default)
			)
			(layer "B.Fab")
		)
		(fp_line
			(start 0.32512 -0.175006)
			(end -0.32512 -0.175006)
			(stroke
				(width 0.1)
				(type default)
			)
			(layer "B.Fab")
		)
		(fp_line
			(start 0.32512 0.175006)
			(end 0.32512 -0.175006)
			(stroke
				(width 0.1)
				(type default)
			)
			(layer "B.Fab")
		)
		(pad "1" smd rect
			(at 0.2667 0 180)
			(size 0.3048 0.381)
			(layers "B.Cu" "B.Mask" "B.Paste")
			(net "P1V8_CPU1_RT_1D")
		)
		(pad "2" smd rect
			(at -0.2667 0)
			(size 0.3048 0.381)
			(layers "B.Cu" "B.Mask" "B.Paste")
			(net "SMB_RT_CPU1_P0_ROM_MUX_2D_R_SCL")
		)
	)
	(footprint ""
		(layer "B.Cu")
		(at 291.52469 -193.99631)
		(property "Reference" "C96"
			(at 0 0 0)
			(layer "B.SilkS")
			(hide yes)
			(effects
				(font
					(size 1.27 1.27)
				)
				(justify mirror)
			)
		)
		(property "Value" ""
			(at 0 0 0)
			(layer "B.Fab")
			(effects
				(font
					(size 1.27 1.27)
				)
				(justify mirror)
			)
		)
		(duplicate_pad_numbers_are_jumpers no)
		(fp_line
			(start -0.7874 -0.4064)
			(end -0.7874 0.4064)
			(stroke
				(width 0.1524)
				(type default)
			)
			(layer "B.SilkS")
		)
		(fp_line
			(start -0.7874 0.4064)
			(end 0.7874 0.4064)
			(stroke
				(width 0.1524)
				(type default)
			)
			(layer "B.SilkS")
		)
		(fp_line
			(start 0.7874 -0.4064)
			(end -0.7874 -0.4064)
			(stroke
				(width 0.1524)
				(type default)
			)
			(layer "B.SilkS")
		)
		(fp_line
			(start 0.7874 0.4064)
			(end 0.7874 -0.4064)
			(stroke
				(width 0.1524)
				(type default)
			)
			(layer "B.SilkS")
		)
		(fp_line
			(start -0.67945 -0.3048)
			(end -0.67945 0.3048)
			(stroke
				(width 0.1)
				(type default)
			)
			(layer "B.Fab")
		)
		(fp_line
			(start -0.67945 0.3048)
			(end -0.120396 0.3048)
			(stroke
				(width 0.1)
				(type default)
			)
			(layer "B.Fab")
		)
		(fp_line
			(start -0.12065 -0.3048)
			(end -0.67945 -0.3048)
			(stroke
				(width 0.1)
				(type default)
			)
			(layer "B.Fab")
		)
		(fp_line
			(start -0.12065 -0.2794)
			(end -0.12065 -0.3048)
			(stroke
				(width 0.1)
				(type default)
			)
			(layer "B.Fab")
		)
		(fp_line
			(start -0.120396 0.2794)
			(end 0.12065 0.2794)
			(stroke
				(width 0.1)
				(type default)
			)
			(layer "B.Fab")
		)
		(fp_line
			(start -0.120396 0.3048)
			(end -0.120396 0.2794)
			(stroke
				(width 0.1)
				(type default)
			)
			(layer "B.Fab")
		)
		(fp_line
			(start 0.12065 -0.305054)
			(end 0.12065 -0.2794)
			(stroke
				(width 0.1)
				(type default)
			)
			(layer "B.Fab")
		)
		(fp_line
			(start 0.12065 -0.2794)
			(end -0.12065 -0.2794)
			(stroke
				(width 0.1)
				(type default)
			)
			(layer "B.Fab")
		)
		(fp_line
			(start 0.12065 0.2794)
			(end 0.12065 0.3048)
			(stroke
				(width 0.1)
				(type default)
			)
			(layer "B.Fab")
		)
		(fp_line
			(start 0.12065 0.3048)
			(end 0.67945 0.3048)
			(stroke
				(width 0.1)
				(type default)
			)
			(layer "B.Fab")
		)
		(fp_line
			(start 0.67945 -0.305054)
			(end 0.12065 -0.305054)
			(stroke
				(width 0.1)
				(type default)
			)
			(layer "B.Fab")
		)
		(fp_line
			(start 0.67945 0.3048)
			(end 0.67945 -0.305054)
			(stroke
				(width 0.1)
				(type default)
			)
			(layer "B.Fab")
		)
		(pad "1" smd circle
			(at 0.40005 0 180)
			(size 0 0)
			(layers "B.Cu" "B.Mask" "B.Paste")
			(net "P3V3_AUX")
		)
		(pad "2" smd circle
			(at -0.40005 0 180)
			(size 0 0)
			(layers "B.Cu" "B.Mask" "B.Paste")
			(net "GND")
		)
	)
	(footprint ""
		(layer "B.Cu")
		(at 410.21889 -398.942052 90)
		(property "Reference" "C971"
			(at 0 0 90)
			(layer "B.SilkS")
			(hide yes)
			(effects
				(font
					(size 1.27 1.27)
				)
				(justify mirror)
			)
		)
		(property "Value" ""
			(at 0 0 90)
			(layer "B.Fab")
			(effects
				(font
					(size 1.27 1.27)
				)
				(justify mirror)
			)
		)
		(duplicate_pad_numbers_are_jumpers no)
		(fp_line
			(start 0.7874 -0.4064)
			(end -0.7874 -0.4064)
			(stroke
				(width 0.1524)
				(type default)
			)
			(layer "B.SilkS")
		)
		(fp_line
			(start -0.7874 -0.4064)
			(end -0.7874 0.4064)
			(stroke
				(width 0.1524)
				(type default)
			)
			(layer "B.SilkS")
		)
		(fp_line
			(start 0.7874 0.4064)
			(end 0.7874 -0.4064)
			(stroke
				(width 0.1524)
				(type default)
			)
			(layer "B.SilkS")
		)
		(fp_line
			(start -0.7874 0.4064)
			(end 0.7874 0.4064)
			(stroke
				(width 0.1524)
				(type default)
			)
			(layer "B.SilkS")
		)
		(fp_line
			(start 0.67945 -0.305054)
			(end 0.12065 -0.305054)
			(stroke
				(width 0.1)
				(type default)
			)
			(layer "B.Fab")
		)
		(fp_line
			(start 0.12065 -0.305054)
			(end 0.12065 -0.2794)
			(stroke
				(width 0.1)
				(type default)
			)
			(layer "B.Fab")
		)
		(fp_line
			(start -0.12065 -0.3048)
			(end -0.67945 -0.3048)
			(stroke
				(width 0.1)
				(type default)
			)
			(layer "B.Fab")
		)
		(fp_line
			(start -0.67945 -0.3048)
			(end -0.67945 0.3048)
			(stroke
				(width 0.1)
				(type default)
			)
			(layer "B.Fab")
		)
		(fp_line
			(start 0.12065 -0.2794)
			(end -0.12065 -0.2794)
			(stroke
				(width 0.1)
				(type default)
			)
			(layer "B.Fab")
		)
		(fp_line
			(start -0.12065 -0.2794)
			(end -0.12065 -0.3048)
			(stroke
				(width 0.1)
				(type default)
			)
			(layer "B.Fab")
		)
		(fp_line
			(start 0.12065 0.2794)
			(end 0.12065 0.3048)
			(stroke
				(width 0.1)
				(type default)
			)
			(layer "B.Fab")
		)
		(fp_line
			(start -0.120396 0.2794)
			(end 0.12065 0.2794)
			(stroke
				(width 0.1)
				(type default)
			)
			(layer "B.Fab")
		)
		(fp_line
			(start 0.67945 0.3048)
			(end 0.67945 -0.305054)
			(stroke
				(width 0.1)
				(type default)
			)
			(layer "B.Fab")
		)
		(fp_line
			(start 0.12065 0.3048)
			(end 0.67945 0.3048)
			(stroke
				(width 0.1)
				(type default)
			)
			(layer "B.Fab")
		)
		(fp_line
			(start -0.120396 0.3048)
			(end -0.120396 0.2794)
			(stroke
				(width 0.1)
				(type default)
			)
			(layer "B.Fab")
		)
		(fp_line
			(start -0.67945 0.3048)
			(end -0.120396 0.3048)
			(stroke
				(width 0.1)
				(type default)
			)
			(layer "B.Fab")
		)
		(pad "1" smd circle
			(at 0.40005 0 270)
			(size 0 0)
			(layers "B.Cu" "B.Mask" "B.Paste")
			(net "P0V9_CPU0_RT_2D")
		)
		(pad "2" smd circle
			(at -0.40005 0 270)
			(size 0 0)
			(layers "B.Cu" "B.Mask" "B.Paste")
			(net "GND")
		)
	)
)
